(kicad_pcb
	(version 20260206)
	(generator "pcbnew")
	(generator_version "10.0")
	(general
		(thickness 1.6)
		(legacy_teardrops no)
	)
	(paper "A4")
	(title_block
		(title "04192023_DAF0TMB3IC0_F0TG_MB_C_brd_V02_OCP.brd")
		(comment 1 "Grand Teton / footprints 4751-4757 of 8354")
	)
	(layers
		(0 "F.Cu" signal "TOP")
		(4 "In1.Cu" signal "GND")
		(6 "In2.Cu" signal "IN1")
		(8 "In3.Cu" signal "GND1")
		(10 "In4.Cu" signal "IN2")
		(12 "In5.Cu" signal "GND2")
		(14 "In6.Cu" signal "IN3")
		(16 "In7.Cu" signal "GND3")
		(18 "In8.Cu" signal "VCC")
		(20 "In9.Cu" signal "VCC1")
		(22 "In10.Cu" signal "GND4")
		(24 "In11.Cu" signal "IN4")
		(26 "In12.Cu" signal "GND5")
		(28 "In13.Cu" signal "IN5")
		(30 "In14.Cu" signal "GND6")
		(32 "In15.Cu" signal "IN6")
		(34 "In16.Cu" signal "GND7")
		(2 "B.Cu" signal "BOTTOM")
		(9 "F.Adhes" user "F.Adhesive")
		(11 "B.Adhes" user "B.Adhesive")
		(13 "F.Paste" user "Package Geometry/Pastemask Top")
		(15 "B.Paste" user "Package Geometry/Pastemask Bottom")
		(5 "F.SilkS" user "Ref Des/Silkscreen Top")
		(7 "B.SilkS" user "Ref Des/Silkscreen Bottom")
		(1 "F.Mask" user "Board Geometry/Soldermask Top")
		(3 "B.Mask" user "Board Geometry/Soldermask Bottom")
		(17 "Dwgs.User" user "User.Drawings")
		(19 "Cmts.User" user "User.Comments")
		(21 "Eco1.User" user "User.Eco1")
		(23 "Eco2.User" user "User.Eco2")
		(25 "Edge.Cuts" user "Board Geometry/Outline")
		(27 "Margin" user)
		(31 "F.CrtYd" user "Package Geometry/Place Bound Top")
		(29 "B.CrtYd" user "Package Geometry/Place Bound Bottom")
		(35 "F.Fab" user "Ref Des/Assembly Top")
		(33 "B.Fab" user "Ref Des/Assembly Bottom")
	)
	(footprint ""
		(layer "F.Cu")
		(at 319.940178 -41.668954)
		(property "Reference" "C2047"
			(at 0 0 0)
			(layer "F.SilkS")
			(hide yes)
			(effects
				(font
					(size 1.27 1.27)
				)
			)
		)
		(property "Value" ""
			(at 0 0 0)
			(layer "F.Fab")
			(effects
				(font
					(size 1.27 1.27)
				)
			)
		)
		(duplicate_pad_numbers_are_jumpers no)
		(fp_line
			(start -0.7874 -0.4064)
			(end 0.7874 -0.4064)
			(stroke
				(width 0.1524)
				(type default)
			)
			(layer "F.SilkS")
		)
		(fp_line
			(start -0.7874 0.4064)
			(end -0.7874 -0.4064)
			(stroke
				(width 0.1524)
				(type default)
			)
			(layer "F.SilkS")
		)
		(fp_line
			(start 0.7874 -0.4064)
			(end 0.7874 0.4064)
			(stroke
				(width 0.1524)
				(type default)
			)
			(layer "F.SilkS")
		)
		(fp_line
			(start 0.7874 0.4064)
			(end -0.7874 0.4064)
			(stroke
				(width 0.1524)
				(type default)
			)
			(layer "F.SilkS")
		)
		(fp_line
			(start -0.67945 -0.305054)
			(end -0.12065 -0.305054)
			(stroke
				(width 0.1)
				(type default)
			)
			(layer "F.Fab")
		)
		(fp_line
			(start -0.67945 0.3048)
			(end -0.67945 -0.305054)
			(stroke
				(width 0.1)
				(type default)
			)
			(layer "F.Fab")
		)
		(fp_line
			(start -0.12065 -0.305054)
			(end -0.12065 -0.2794)
			(stroke
				(width 0.1)
				(type default)
			)
			(layer "F.Fab")
		)
		(fp_line
			(start -0.12065 -0.2794)
			(end 0.12065 -0.2794)
			(stroke
				(width 0.1)
				(type default)
			)
			(layer "F.Fab")
		)
		(fp_line
			(start -0.12065 0.2794)
			(end -0.12065 0.3048)
			(stroke
				(width 0.1)
				(type default)
			)
			(layer "F.Fab")
		)
		(fp_line
			(start -0.12065 0.3048)
			(end -0.67945 0.3048)
			(stroke
				(width 0.1)
				(type default)
			)
			(layer "F.Fab")
		)
		(fp_line
			(start 0.120396 0.2794)
			(end -0.12065 0.2794)
			(stroke
				(width 0.1)
				(type default)
			)
			(layer "F.Fab")
		)
		(fp_line
			(start 0.120396 0.3048)
			(end 0.120396 0.2794)
			(stroke
				(width 0.1)
				(type default)
			)
			(layer "F.Fab")
		)
		(fp_line
			(start 0.12065 -0.3048)
			(end 0.67945 -0.3048)
			(stroke
				(width 0.1)
				(type default)
			)
			(layer "F.Fab")
		)
		(fp_line
			(start 0.12065 -0.2794)
			(end 0.12065 -0.3048)
			(stroke
				(width 0.1)
				(type default)
			)
			(layer "F.Fab")
		)
		(fp_line
			(start 0.67945 -0.3048)
			(end 0.67945 0.3048)
			(stroke
				(width 0.1)
				(type default)
			)
			(layer "F.Fab")
		)
		(fp_line
			(start 0.67945 0.3048)
			(end 0.120396 0.3048)
			(stroke
				(width 0.1)
				(type default)
			)
			(layer "F.Fab")
		)
		(pad "1" smd circle
			(at -0.40005 0)
			(size 0 0)
			(layers "F.Cu" "F.Mask" "F.Paste")
			(net "P3V3_AUX_ADC_TIC")
		)
		(pad "2" smd circle
			(at 0.40005 0)
			(size 0 0)
			(layers "F.Cu" "F.Mask" "F.Paste")
			(net "GND")
		)
	)
	(footprint ""
		(layer "F.Cu")
		(at 320.153538 -116.632228 180)
		(property "Reference" "R26"
			(at 0 0 180)
			(layer "F.SilkS")
			(hide yes)
			(effects
				(font
					(size 1.27 1.27)
				)
			)
		)
		(property "Value" ""
			(at 0 0 180)
			(layer "F.Fab")
			(effects
				(font
					(size 1.27 1.27)
				)
			)
		)
		(duplicate_pad_numbers_are_jumpers no)
		(fp_line
			(start 0.7874 0.4064)
			(end -0.7874 0.4064)
			(stroke
				(width 0.1524)
				(type default)
			)
			(layer "F.SilkS")
		)
		(fp_line
			(start 0.7874 -0.4064)
			(end 0.7874 0.4064)
			(stroke
				(width 0.1524)
				(type default)
			)
			(layer "F.SilkS")
		)
		(fp_line
			(start -0.7874 0.4064)
			(end -0.7874 -0.4064)
			(stroke
				(width 0.1524)
				(type default)
			)
			(layer "F.SilkS")
		)
		(fp_line
			(start -0.7874 -0.4064)
			(end 0.7874 -0.4064)
			(stroke
				(width 0.1524)
				(type default)
			)
			(layer "F.SilkS")
		)
		(fp_line
			(start 0.67945 0.3048)
			(end 0.120396 0.3048)
			(stroke
				(width 0.1)
				(type default)
			)
			(layer "F.Fab")
		)
		(fp_line
			(start 0.67945 -0.3048)
			(end 0.67945 0.3048)
			(stroke
				(width 0.1)
				(type default)
			)
			(layer "F.Fab")
		)
		(fp_line
			(start 0.12065 -0.2794)
			(end 0.12065 -0.3048)
			(stroke
				(width 0.1)
				(type default)
			)
			(layer "F.Fab")
		)
		(fp_line
			(start 0.12065 -0.3048)
			(end 0.67945 -0.3048)
			(stroke
				(width 0.1)
				(type default)
			)
			(layer "F.Fab")
		)
		(fp_line
			(start 0.120396 0.3048)
			(end 0.120396 0.2794)
			(stroke
				(width 0.1)
				(type default)
			)
			(layer "F.Fab")
		)
		(fp_line
			(start 0.120396 0.2794)
			(end -0.12065 0.2794)
			(stroke
				(width 0.1)
				(type default)
			)
			(layer "F.Fab")
		)
		(fp_line
			(start -0.12065 0.3048)
			(end -0.67945 0.3048)
			(stroke
				(width 0.1)
				(type default)
			)
			(layer "F.Fab")
		)
		(fp_line
			(start -0.12065 0.2794)
			(end -0.12065 0.3048)
			(stroke
				(width 0.1)
				(type default)
			)
			(layer "F.Fab")
		)
		(fp_line
			(start -0.12065 -0.2794)
			(end 0.12065 -0.2794)
			(stroke
				(width 0.1)
				(type default)
			)
			(layer "F.Fab")
		)
		(fp_line
			(start -0.12065 -0.305054)
			(end -0.12065 -0.2794)
			(stroke
				(width 0.1)
				(type default)
			)
			(layer "F.Fab")
		)
		(fp_line
			(start -0.67945 0.3048)
			(end -0.67945 -0.305054)
			(stroke
				(width 0.1)
				(type default)
			)
			(layer "F.Fab")
		)
		(fp_line
			(start -0.67945 -0.305054)
			(end -0.12065 -0.305054)
			(stroke
				(width 0.1)
				(type default)
			)
			(layer "F.Fab")
		)
		(pad "1" smd circle
			(at -0.40005 0 180)
			(size 0 0)
			(layers "F.Cu" "F.Mask" "F.Paste")
			(net "P3V3_AUX")
		)
		(pad "2" smd circle
			(at 0.40005 0 180)
			(size 0 0)
			(layers "F.Cu" "F.Mask" "F.Paste")
			(net "SMB_FRU_3V3AUX_R1_SCL")
		)
	)
	(footprint ""
		(layer "F.Cu")
		(at 17.190974 -92.687648 90)
		(property "Reference" "R3662"
			(at 0 0 90)
			(layer "F.SilkS")
			(hide yes)
			(effects
				(font
					(size 1.27 1.27)
				)
			)
		)
		(property "Value" ""
			(at 0 0 90)
			(layer "F.Fab")
			(effects
				(font
					(size 1.27 1.27)
				)
			)
		)
		(duplicate_pad_numbers_are_jumpers no)
		(fp_line
			(start 0.7874 -0.4064)
			(end 0.7874 0.4064)
			(stroke
				(width 0.1524)
				(type default)
			)
			(layer "F.SilkS")
		)
		(fp_line
			(start -0.7874 -0.4064)
			(end 0.7874 -0.4064)
			(stroke
				(width 0.1524)
				(type default)
			)
			(layer "F.SilkS")
		)
		(fp_line
			(start 0.7874 0.4064)
			(end -0.7874 0.4064)
			(stroke
				(width 0.1524)
				(type default)
			)
			(layer "F.SilkS")
		)
		(fp_line
			(start -0.7874 0.4064)
			(end -0.7874 -0.4064)
			(stroke
				(width 0.1524)
				(type default)
			)
			(layer "F.SilkS")
		)
		(fp_line
			(start -0.12065 -0.305054)
			(end -0.12065 -0.2794)
			(stroke
				(width 0.1)
				(type default)
			)
			(layer "F.Fab")
		)
		(fp_line
			(start -0.67945 -0.305054)
			(end -0.12065 -0.305054)
			(stroke
				(width 0.1)
				(type default)
			)
			(layer "F.Fab")
		)
		(fp_line
			(start 0.67945 -0.3048)
			(end 0.67945 0.3048)
			(stroke
				(width 0.1)
				(type default)
			)
			(layer "F.Fab")
		)
		(fp_line
			(start 0.12065 -0.3048)
			(end 0.67945 -0.3048)
			(stroke
				(width 0.1)
				(type default)
			)
			(layer "F.Fab")
		)
		(fp_line
			(start 0.12065 -0.2794)
			(end 0.12065 -0.3048)
			(stroke
				(width 0.1)
				(type default)
			)
			(layer "F.Fab")
		)
		(fp_line
			(start -0.12065 -0.2794)
			(end 0.12065 -0.2794)
			(stroke
				(width 0.1)
				(type default)
			)
			(layer "F.Fab")
		)
		(fp_line
			(start 0.120396 0.2794)
			(end -0.12065 0.2794)
			(stroke
				(width 0.1)
				(type default)
			)
			(layer "F.Fab")
		)
		(fp_line
			(start -0.12065 0.2794)
			(end -0.12065 0.3048)
			(stroke
				(width 0.1)
				(type default)
			)
			(layer "F.Fab")
		)
		(fp_line
			(start 0.67945 0.3048)
			(end 0.120396 0.3048)
			(stroke
				(width 0.1)
				(type default)
			)
			(layer "F.Fab")
		)
		(fp_line
			(start 0.120396 0.3048)
			(end 0.120396 0.2794)
			(stroke
				(width 0.1)
				(type default)
			)
			(layer "F.Fab")
		)
		(fp_line
			(start -0.12065 0.3048)
			(end -0.67945 0.3048)
			(stroke
				(width 0.1)
				(type default)
			)
			(layer "F.Fab")
		)
		(fp_line
			(start -0.67945 0.3048)
			(end -0.67945 -0.305054)
			(stroke
				(width 0.1)
				(type default)
			)
			(layer "F.Fab")
		)
		(pad "1" smd circle
			(at -0.40005 0 90)
			(size 0 0)
			(layers "F.Cu" "F.Mask" "F.Paste")
			(net "P3V3_AUX_USB_HUB")
		)
		(pad "2" smd circle
			(at 0.40005 0 90)
			(size 0 0)
			(layers "F.Cu" "F.Mask" "F.Paste")
			(net "USB_HUB_DVDD")
		)
	)
	(footprint ""
		(layer "F.Cu")
		(at 291.259006 -398.60855 90)
		(property "Reference" "R679"
			(at 0 0 90)
			(layer "F.SilkS")
			(hide yes)
			(effects
				(font
					(size 1.27 1.27)
				)
			)
		)
		(property "Value" ""
			(at 0 0 90)
			(layer "F.Fab")
			(effects
				(font
					(size 1.27 1.27)
				)
			)
		)
		(duplicate_pad_numbers_are_jumpers no)
		(fp_line
			(start 0.32512 -0.175006)
			(end 0.32512 0.175006)
			(stroke
				(width 0.1)
				(type default)
			)
			(layer "F.Fab")
		)
		(fp_line
			(start -0.32512 -0.175006)
			(end 0.32512 -0.175006)
			(stroke
				(width 0.1)
				(type default)
			)
			(layer "F.Fab")
		)
		(fp_line
			(start 0.32512 0.175006)
			(end -0.32512 0.175006)
			(stroke
				(width 0.1)
				(type default)
			)
			(layer "F.Fab")
		)
		(fp_line
			(start -0.32512 0.175006)
			(end -0.32512 -0.175006)
			(stroke
				(width 0.1)
				(type default)
			)
			(layer "F.Fab")
		)
		(pad "1" smd rect
			(at -0.2667 0 90)
			(size 0.3048 0.381)
			(layers "F.Cu" "F.Mask" "F.Paste")
			(net "SMB_RT_CPU0_P1_ROM_R_SDA")
		)
		(pad "2" smd rect
			(at 0.2667 0 270)
			(size 0.3048 0.381)
			(layers "F.Cu" "F.Mask" "F.Paste")
			(net "SMB_RT_CPU0_P1_ROM_SDA")
		)
	)
	(footprint ""
		(layer "F.Cu")
		(at 186.111642 -413.64408 90)
		(property "Reference" "R9001"
			(at 0 0 90)
			(layer "F.SilkS")
			(hide yes)
			(effects
				(font
					(size 1.27 1.27)
				)
			)
		)
		(property "Value" ""
			(at 0 0 90)
			(layer "F.Fab")
			(effects
				(font
					(size 1.27 1.27)
				)
			)
		)
		(duplicate_pad_numbers_are_jumpers no)
		(fp_line
			(start 0.7874 -0.4064)
			(end 0.7874 0.4064)
			(stroke
				(width 0.1524)
				(type default)
			)
			(layer "F.SilkS")
		)
		(fp_line
			(start -0.7874 -0.4064)
			(end 0.7874 -0.4064)
			(stroke
				(width 0.1524)
				(type default)
			)
			(layer "F.SilkS")
		)
		(fp_line
			(start 0.7874 0.4064)
			(end -0.7874 0.4064)
			(stroke
				(width 0.1524)
				(type default)
			)
			(layer "F.SilkS")
		)
		(fp_line
			(start -0.7874 0.4064)
			(end -0.7874 -0.4064)
			(stroke
				(width 0.1524)
				(type default)
			)
			(layer "F.SilkS")
		)
		(fp_line
			(start -0.12065 -0.305054)
			(end -0.12065 -0.2794)
			(stroke
				(width 0.1)
				(type default)
			)
			(layer "F.Fab")
		)
		(fp_line
			(start -0.67945 -0.305054)
			(end -0.12065 -0.305054)
			(stroke
				(width 0.1)
				(type default)
			)
			(layer "F.Fab")
		)
		(fp_line
			(start 0.67945 -0.3048)
			(end 0.67945 0.3048)
			(stroke
				(width 0.1)
				(type default)
			)
			(layer "F.Fab")
		)
		(fp_line
			(start 0.12065 -0.3048)
			(end 0.67945 -0.3048)
			(stroke
				(width 0.1)
				(type default)
			)
			(layer "F.Fab")
		)
		(fp_line
			(start 0.12065 -0.2794)
			(end 0.12065 -0.3048)
			(stroke
				(width 0.1)
				(type default)
			)
			(layer "F.Fab")
		)
		(fp_line
			(start -0.12065 -0.2794)
			(end 0.12065 -0.2794)
			(stroke
				(width 0.1)
				(type default)
			)
			(layer "F.Fab")
		)
		(fp_line
			(start 0.120396 0.2794)
			(end -0.12065 0.2794)
			(stroke
				(width 0.1)
				(type default)
			)
			(layer "F.Fab")
		)
		(fp_line
			(start -0.12065 0.2794)
			(end -0.12065 0.3048)
			(stroke
				(width 0.1)
				(type default)
			)
			(layer "F.Fab")
		)
		(fp_line
			(start 0.67945 0.3048)
			(end 0.120396 0.3048)
			(stroke
				(width 0.1)
				(type default)
			)
			(layer "F.Fab")
		)
		(fp_line
			(start 0.120396 0.3048)
			(end 0.120396 0.2794)
			(stroke
				(width 0.1)
				(type default)
			)
			(layer "F.Fab")
		)
		(fp_line
			(start -0.12065 0.3048)
			(end -0.67945 0.3048)
			(stroke
				(width 0.1)
				(type default)
			)
			(layer "F.Fab")
		)
		(fp_line
			(start -0.67945 0.3048)
			(end -0.67945 -0.305054)
			(stroke
				(width 0.1)
				(type default)
			)
			(layer "F.Fab")
		)
		(pad "1" smd circle
			(at -0.40005 0 90)
			(size 0 0)
			(layers "F.Cu" "F.Mask" "F.Paste")
			(net "GPU_PRSNT_N_ISO")
		)
		(pad "2" smd circle
			(at 0.40005 0 90)
			(size 0 0)
			(layers "F.Cu" "F.Mask" "F.Paste")
			(net "GPU_PRSNT_N_ISO_R1")
		)
	)
	(footprint ""
		(layer "F.Cu")
		(at 9.379458 -423.821098)
		(property "Reference" "R6171"
			(at 0 0 0)
			(layer "F.SilkS")
			(hide yes)
			(effects
				(font
					(size 1.27 1.27)
				)
			)
		)
		(property "Value" ""
			(at 0 0 0)
			(layer "F.Fab")
			(effects
				(font
					(size 1.27 1.27)
				)
			)
		)
		(duplicate_pad_numbers_are_jumpers no)
		(fp_line
			(start -0.7874 -0.4064)
			(end 0.7874 -0.4064)
			(stroke
				(width 0.1524)
				(type default)
			)
			(layer "F.SilkS")
		)
		(fp_line
			(start -0.7874 0.4064)
			(end -0.7874 -0.4064)
			(stroke
				(width 0.1524)
				(type default)
			)
			(layer "F.SilkS")
		)
		(fp_line
			(start 0.7874 -0.4064)
			(end 0.7874 0.4064)
			(stroke
				(width 0.1524)
				(type default)
			)
			(layer "F.SilkS")
		)
		(fp_line
			(start 0.7874 0.4064)
			(end -0.7874 0.4064)
			(stroke
				(width 0.1524)
				(type default)
			)
			(layer "F.SilkS")
		)
		(fp_line
			(start -0.67945 -0.305054)
			(end -0.12065 -0.305054)
			(stroke
				(width 0.1)
				(type default)
			)
			(layer "F.Fab")
		)
		(fp_line
			(start -0.67945 0.3048)
			(end -0.67945 -0.305054)
			(stroke
				(width 0.1)
				(type default)
			)
			(layer "F.Fab")
		)
		(fp_line
			(start -0.12065 -0.305054)
			(end -0.12065 -0.2794)
			(stroke
				(width 0.1)
				(type default)
			)
			(layer "F.Fab")
		)
		(fp_line
			(start -0.12065 -0.2794)
			(end 0.12065 -0.2794)
			(stroke
				(width 0.1)
				(type default)
			)
			(layer "F.Fab")
		)
		(fp_line
			(start -0.12065 0.2794)
			(end -0.12065 0.3048)
			(stroke
				(width 0.1)
				(type default)
			)
			(layer "F.Fab")
		)
		(fp_line
			(start -0.12065 0.3048)
			(end -0.67945 0.3048)
			(stroke
				(width 0.1)
				(type default)
			)
			(layer "F.Fab")
		)
		(fp_line
			(start 0.120396 0.2794)
			(end -0.12065 0.2794)
			(stroke
				(width 0.1)
				(type default)
			)
			(layer "F.Fab")
		)
		(fp_line
			(start 0.120396 0.3048)
			(end 0.120396 0.2794)
			(stroke
				(width 0.1)
				(type default)
			)
			(layer "F.Fab")
		)
		(fp_line
			(start 0.12065 -0.3048)
			(end 0.67945 -0.3048)
			(stroke
				(width 0.1)
				(type default)
			)
			(layer "F.Fab")
		)
		(fp_line
			(start 0.12065 -0.2794)
			(end 0.12065 -0.3048)
			(stroke
				(width 0.1)
				(type default)
			)
			(layer "F.Fab")
		)
		(fp_line
			(start 0.67945 -0.3048)
			(end 0.67945 0.3048)
			(stroke
				(width 0.1)
				(type default)
			)
			(layer "F.Fab")
		)
		(fp_line
			(start 0.67945 0.3048)
			(end 0.120396 0.3048)
			(stroke
				(width 0.1)
				(type default)
			)
			(layer "F.Fab")
		)
		(pad "1" smd circle
			(at -0.40005 0)
			(size 0 0)
			(layers "F.Cu" "F.Mask" "F.Paste")
			(net "P3V3_AUX")
		)
		(pad "2" smd circle
			(at 0.40005 0)
			(size 0 0)
			(layers "F.Cu" "F.Mask" "F.Paste")
			(net "FM_P2E_BUF2_EQA1")
		)
	)
	(footprint ""
		(layer "F.Cu")
		(at 193.167 -133.568948 90)
		(property "Reference" "R372"
			(at 0 0 90)
			(layer "F.SilkS")
			(hide yes)
			(effects
				(font
					(size 1.27 1.27)
				)
			)
		)
		(property "Value" ""
			(at 0 0 90)
			(layer "F.Fab")
			(effects
				(font
					(size 1.27 1.27)
				)
			)
		)
		(duplicate_pad_numbers_are_jumpers no)
		(fp_line
			(start 0.7874 -0.4064)
			(end 0.7874 0.4064)
			(stroke
				(width 0.1524)
				(type default)
			)
			(layer "F.SilkS")
		)
		(fp_line
			(start -0.7874 -0.4064)
			(end 0.7874 -0.4064)
			(stroke
				(width 0.1524)
				(type default)
			)
			(layer "F.SilkS")
		)
		(fp_line
			(start 0.7874 0.4064)
			(end -0.7874 0.4064)
			(stroke
				(width 0.1524)
				(type default)
			)
			(layer "F.SilkS")
		)
		(fp_line
			(start -0.7874 0.4064)
			(end -0.7874 -0.4064)
			(stroke
				(width 0.1524)
				(type default)
			)
			(layer "F.SilkS")
		)
		(fp_line
			(start -0.12065 -0.305054)
			(end -0.12065 -0.2794)
			(stroke
				(width 0.1)
				(type default)
			)
			(layer "F.Fab")
		)
		(fp_line
			(start -0.67945 -0.305054)
			(end -0.12065 -0.305054)
			(stroke
				(width 0.1)
				(type default)
			)
			(layer "F.Fab")
		)
		(fp_line
			(start 0.67945 -0.3048)
			(end 0.67945 0.3048)
			(stroke
				(width 0.1)
				(type default)
			)
			(layer "F.Fab")
		)
		(fp_line
			(start 0.12065 -0.3048)
			(end 0.67945 -0.3048)
			(stroke
				(width 0.1)
				(type default)
			)
			(layer "F.Fab")
		)
		(fp_line
			(start 0.12065 -0.2794)
			(end 0.12065 -0.3048)
			(stroke
				(width 0.1)
				(type default)
			)
			(layer "F.Fab")
		)
		(fp_line
			(start -0.12065 -0.2794)
			(end 0.12065 -0.2794)
			(stroke
				(width 0.1)
				(type default)
			)
			(layer "F.Fab")
		)
		(fp_line
			(start 0.120396 0.2794)
			(end -0.12065 0.2794)
			(stroke
				(width 0.1)
				(type default)
			)
			(layer "F.Fab")
		)
		(fp_line
			(start -0.12065 0.2794)
			(end -0.12065 0.3048)
			(stroke
				(width 0.1)
				(type default)
			)
			(layer "F.Fab")
		)
		(fp_line
			(start 0.67945 0.3048)
			(end 0.120396 0.3048)
			(stroke
				(width 0.1)
				(type default)
			)
			(layer "F.Fab")
		)
		(fp_line
			(start 0.120396 0.3048)
			(end 0.120396 0.2794)
			(stroke
				(width 0.1)
				(type default)
			)
			(layer "F.Fab")
		)
		(fp_line
			(start -0.12065 0.3048)
			(end -0.67945 0.3048)
			(stroke
				(width 0.1)
				(type default)
			)
			(layer "F.Fab")
		)
		(fp_line
			(start -0.67945 0.3048)
			(end -0.67945 -0.305054)
			(stroke
				(width 0.1)
				(type default)
			)
			(layer "F.Fab")
		)
		(pad "1" smd circle
			(at -0.40005 0 90)
			(size 0 0)
			(layers "F.Cu" "F.Mask" "F.Paste")
			(net "P12V_ALL_PWROK_R")
		)
		(pad "2" smd circle
			(at 0.40005 0 90)
			(size 0 0)
			(layers "F.Cu" "F.Mask" "F.Paste")
			(net "P12V_ALL_PWROK")
		)
	)
)
